# T6G (Grand Teton) — schematic netlist excerpt (pin names and nets, part order shuffled) for the footprints in the layout excerpt that follows; sources: Cadence DE-HDL packaged netlist, KiCad conversion of 04192023_DAF0TMB3IC0_F0TG_MB_C_brd_V02_OCP.brd

PC290_3  Q_CAP  0.1UF 25V 10% X7R  pkg 0402  page 212 : A = SW_P12V_AUX_PVDDCR_CPU0_P1_FLT ; B = GND
R4078  Q_RES  10K 1% EMPTY  pkg 0402LF  page 233 : A = P3V3_AUX ; B = FG_SS_EN

(kicad_pcb
	(version 20260206)
	(generator "pcbnew")
	(generator_version "10.0")
	(general
		(thickness 1.6)
		(legacy_teardrops no)
	)
	(paper "A4")
	(title_block
		(title "04192023_DAF0TMB3IC0_F0TG_MB_C_brd_V02_OCP.brd")
		(comment 1 "Grand Teton / footprints 3899-3901 of 8354")
	)
	(layers
		(0 "F.Cu" signal "TOP")
		(4 "In1.Cu" signal "GND")
		(6 "In2.Cu" signal "IN1")
		(8 "In3.Cu" signal "GND1")
		(10 "In4.Cu" signal "IN2")
		(12 "In5.Cu" signal "GND2")
		(14 "In6.Cu" signal "IN3")
		(16 "In7.Cu" signal "GND3")
		(18 "In8.Cu" signal "VCC")
		(20 "In9.Cu" signal "VCC1")
		(22 "In10.Cu" signal "GND4")
		(24 "In11.Cu" signal "IN4")
		(26 "In12.Cu" signal "GND5")
		(28 "In13.Cu" signal "IN5")
		(30 "In14.Cu" signal "GND6")
		(32 "In15.Cu" signal "IN6")
		(34 "In16.Cu" signal "GND7")
		(2 "B.Cu" signal "BOTTOM")
		(9 "F.Adhes" user "F.Adhesive")
		(11 "B.Adhes" user "B.Adhesive")
		(13 "F.Paste" user "Package Geometry/Pastemask Top")
		(15 "B.Paste" user "Package Geometry/Pastemask Bottom")
		(5 "F.SilkS" user "Ref Des/Silkscreen Top")
		(7 "B.SilkS" user "Ref Des/Silkscreen Bottom")
		(1 "F.Mask" user "Board Geometry/Soldermask Top")
		(3 "B.Mask" user "Board Geometry/Soldermask Bottom")
		(17 "Dwgs.User" user "User.Drawings")
		(19 "Cmts.User" user "User.Comments")
		(21 "Eco1.User" user "User.Eco1")
		(23 "Eco2.User" user "User.Eco2")
		(25 "Edge.Cuts" user "Board Geometry/Outline")
		(27 "Margin" user)
		(31 "F.CrtYd" user "Package Geometry/Place Bound Top")
		(29 "B.CrtYd" user "Package Geometry/Place Bound Bottom")
		(35 "F.Fab" user "Ref Des/Assembly Top")
		(33 "B.Fab" user "Ref Des/Assembly Bottom")
	)
	(footprint ""
		(layer "F.Cu")
		(at 13.537946 -139.26693 -90)
		(property "Reference" "R4078"
			(at 0 0 270)
			(layer "F.SilkS")
			(hide yes)
			(effects
				(font
					(size 1.27 1.27)
				)
			)
		)
		(property "Value" ""
			(at 0 0 270)
			(layer "F.Fab")
			(effects
				(font
					(size 1.27 1.27)
				)
			)
		)
		(duplicate_pad_numbers_are_jumpers no)
		(fp_line
			(start -0.7874 0.4064)
			(end -0.7874 -0.4064)
			(stroke
				(width 0.1524)
				(type default)
			)
			(layer "F.SilkS")
		)
		(fp_line
			(start 0.7874 0.4064)
			(end -0.7874 0.4064)
			(stroke
				(width 0.1524)
				(type default)
			)
			(layer "F.SilkS")
		)
		(fp_line
			(start -0.7874 -0.4064)
			(end 0.7874 -0.4064)
			(stroke
				(width 0.1524)
				(type default)
			)
			(layer "F.SilkS")
		)
		(fp_line
			(start 0.7874 -0.4064)
			(end 0.7874 0.4064)
			(stroke
				(width 0.1524)
				(type default)
			)
			(layer "F.SilkS")
		)
		(fp_line
			(start -0.67945 0.3048)
			(end -0.67945 -0.305054)
			(stroke
				(width 0.1)
				(type default)
			)
			(layer "F.Fab")
		)
		(fp_line
			(start -0.12065 0.3048)
			(end -0.67945 0.3048)
			(stroke
				(width 0.1)
				(type default)
			)
			(layer "F.Fab")
		)
		(fp_line
			(start 0.120396 0.3048)
			(end 0.120396 0.2794)
			(stroke
				(width 0.1)
				(type default)
			)
			(layer "F.Fab")
		)
		(fp_line
			(start 0.67945 0.3048)
			(end 0.120396 0.3048)
			(stroke
				(width 0.1)
				(type default)
			)
			(layer "F.Fab")
		)
		(fp_line
			(start -0.12065 0.2794)
			(end -0.12065 0.3048)
			(stroke
				(width 0.1)
				(type default)
			)
			(layer "F.Fab")
		)
		(fp_line
			(start 0.120396 0.2794)
			(end -0.12065 0.2794)
			(stroke
				(width 0.1)
				(type default)
			)
			(layer "F.Fab")
		)
		(fp_line
			(start -0.12065 -0.2794)
			(end 0.12065 -0.2794)
			(stroke
				(width 0.1)
				(type default)
			)
			(layer "F.Fab")
		)
		(fp_line
			(start 0.12065 -0.2794)
			(end 0.12065 -0.3048)
			(stroke
				(width 0.1)
				(type default)
			)
			(layer "F.Fab")
		)
		(fp_line
			(start 0.12065 -0.3048)
			(end 0.67945 -0.3048)
			(stroke
				(width 0.1)
				(type default)
			)
			(layer "F.Fab")
		)
		(fp_line
			(start 0.67945 -0.3048)
			(end 0.67945 0.3048)
			(stroke
				(width 0.1)
				(type default)
			)
			(layer "F.Fab")
		)
		(fp_line
			(start -0.67945 -0.305054)
			(end -0.12065 -0.305054)
			(stroke
				(width 0.1)
				(type default)
			)
			(layer "F.Fab")
		)
		(fp_line
			(start -0.12065 -0.305054)
			(end -0.12065 -0.2794)
			(stroke
				(width 0.1)
				(type default)
			)
			(layer "F.Fab")
		)
		(pad "1" smd circle
			(at -0.40005 0 270)
			(size 0 0)
			(layers "F.Cu" "F.Mask" "F.Paste")
			(net "P3V3_AUX")
		)
		(pad "2" smd circle
			(at 0.40005 0 270)
			(size 0 0)
			(layers "F.Cu" "F.Mask" "F.Paste")
			(net "FG_SS_EN")
		)
	)
	(footprint ""
		(layer "F.Cu")
		(at 94.817946 -178.29149 180)
		(property "Reference" "PC290_3"
			(at 0 0 180)
			(layer "F.SilkS")
			(hide yes)
			(effects
				(font
					(size 1.27 1.27)
				)
			)
		)
		(property "Value" ""
			(at 0 0 180)
			(layer "F.Fab")
			(effects
				(font
					(size 1.27 1.27)
				)
			)
		)
		(duplicate_pad_numbers_are_jumpers no)
		(fp_line
			(start 0.7874 0.4064)
			(end -0.7874 0.4064)
			(stroke
				(width 0.1524)
				(type default)
			)
			(layer "F.SilkS")
		)
		(fp_line
			(start 0.7874 -0.4064)
			(end 0.7874 0.4064)
			(stroke
				(width 0.1524)
				(type default)
			)
			(layer "F.SilkS")
		)
		(fp_line
			(start -0.7874 0.4064)
			(end -0.7874 -0.4064)
			(stroke
				(width 0.1524)
				(type default)
			)
			(layer "F.SilkS")
		)
		(fp_line
			(start -0.7874 -0.4064)
			(end 0.7874 -0.4064)
			(stroke
				(width 0.1524)
				(type default)
			)
			(layer "F.SilkS")
		)
		(fp_line
			(start 0.67945 0.3048)
			(end 0.120396 0.3048)
			(stroke
				(width 0.1)
				(type default)
			)
			(layer "F.Fab")
		)
		(fp_line
			(start 0.67945 -0.3048)
			(end 0.67945 0.3048)
			(stroke
				(width 0.1)
				(type default)
			)
			(layer "F.Fab")
		)
		(fp_line
			(start 0.12065 -0.2794)
			(end 0.12065 -0.3048)
			(stroke
				(width 0.1)
				(type default)
			)
			(layer "F.Fab")
		)
		(fp_line
			(start 0.12065 -0.3048)
			(end 0.67945 -0.3048)
			(stroke
				(width 0.1)
				(type default)
			)
			(layer "F.Fab")
		)
		(fp_line
			(start 0.120396 0.3048)
			(end 0.120396 0.2794)
			(stroke
				(width 0.1)
				(type default)
			)
			(layer "F.Fab")
		)
		(fp_line
			(start 0.120396 0.2794)
			(end -0.12065 0.2794)
			(stroke
				(width 0.1)
				(type default)
			)
			(layer "F.Fab")
		)
		(fp_line
			(start -0.12065 0.3048)
			(end -0.67945 0.3048)
			(stroke
				(width 0.1)
				(type default)
			)
			(layer "F.Fab")
		)
		(fp_line
			(start -0.12065 0.2794)
			(end -0.12065 0.3048)
			(stroke
				(width 0.1)
				(type default)
			)
			(layer "F.Fab")
		)
		(fp_line
			(start -0.12065 -0.2794)
			(end 0.12065 -0.2794)
			(stroke
				(width 0.1)
				(type default)
			)
			(layer "F.Fab")
		)
		(fp_line
			(start -0.12065 -0.305054)
			(end -0.12065 -0.2794)
			(stroke
				(width 0.1)
				(type default)
			)
			(layer "F.Fab")
		)
		(fp_line
			(start -0.67945 0.3048)
			(end -0.67945 -0.305054)
			(stroke
				(width 0.1)
				(type default)
			)
			(layer "F.Fab")
		)
		(fp_line
			(start -0.67945 -0.305054)
			(end -0.12065 -0.305054)
			(stroke
				(width 0.1)
				(type default)
			)
			(layer "F.Fab")
		)
		(pad "1" smd circle
			(at -0.40005 0 180)
			(size 0 0)
			(layers "F.Cu" "F.Mask" "F.Paste")
			(net "SW_P12V_AUX_PVDDCR_CPU0_P1_FLT")
		)
		(pad "2" smd circle
			(at 0.40005 0 180)
			(size 0 0)
			(layers "F.Cu" "F.Mask" "F.Paste")
			(net "GND")
		)
	)
	(footprint ""
		(layer "F.Cu")
		(at 301.423324 -489.286042)
		(property "Reference" "ME9"
			(at 0 0 0)
			(layer "F.SilkS")
			(hide yes)
			(effects
				(font
					(size 1.27 1.27)
				)
			)
		)
		(property "Value" ""
			(at 0 0 0)
			(layer "F.Fab")
			(effects
				(font
					(size 1.27 1.27)
				)
			)
		)
		(duplicate_pad_numbers_are_jumpers no)
	)
)
